(kicad_pcb
	(version 20221018)
	(generator pcbnew)
	(general
    (thickness 1.518)
  )
	(paper "A4")
	(title_block
    (title "Kria K26 Devboard")
    (date "2024-03-26")
    (rev "1.2.5")
    (comment 1 "www.antmicro.com")
    (comment 2 "Antmicro Ltd.")
		(comment 9 "footprints 282-289 of 660")
	)
	(layers
    (0 "F.Cu" mixed)
    (1 "In1.Cu" power)
    (2 "In2.Cu" mixed)
    (3 "In3.Cu" power)
    (4 "In4.Cu" mixed)
    (5 "In5.Cu" power)
    (6 "In6.Cu" mixed)
    (31 "B.Cu" power)
    (32 "B.Adhes" user "B.Adhesive")
    (33 "F.Adhes" user "F.Adhesive")
    (34 "B.Paste" user)
    (35 "F.Paste" user)
    (36 "B.SilkS" user "B.Silkscreen")
    (37 "F.SilkS" user "F.Silkscreen")
    (38 "B.Mask" user)
    (39 "F.Mask" user)
    (40 "Dwgs.User" user "User.Drawings")
    (41 "Cmts.User" user "User.Comments")
    (42 "Eco1.User" user "User.Eco1")
    (43 "Eco2.User" user "User.Eco2")
    (44 "Edge.Cuts" user)
    (45 "Margin" user)
    (46 "B.CrtYd" user "B.Courtyard")
    (47 "F.CrtYd" user "F.Courtyard")
    (48 "B.Fab" user)
    (49 "F.Fab" user)
  )
	(footprint "kria-k26-devboard-footprints:R_0402_1005Metric" (layer "F.Cu")
    (at 127.2 118.5 180)
    (descr "Resistor SMD 0402")
    (tags "resistor SMD 0402")
    (property "Author" "Antmicro")
    (property "License" "Apache-2.0")
    (property "MPN" "CR0402-FX-1002GLF")
    (property "Manufacturer" "Bourns")
    (property "Sheetfile" "pcie-m2-key-e.kicad_sch")
    (property "Sheetname" "PCIE M2 key E ")
    (property "Tolerance" "1%")
    (property "Val" "10k")
    (property "ki_description" "10k resistor in 0402 package with 1% tolerance")
    (attr smd)
    (fp_text reference "R153" (at 1.45 -1.35 180) (layer "F.SilkS")
        (effects (font (size 0.7 0.7) (thickness 0.15)) (justify left bottom))
    )
    (fp_text value "R_10k_0402" (at 0 1.4 180) (layer "F.Fab") hide
        (effects (font (size 0.7 0.7) (thickness 0.15)) (justify left bottom))
    )
    (fp_text user "Author: Antmicro" (at -0.95 4.169 180) (layer "F.Fab") hide
        (effects (font (size 0.7 0.7) (thickness 0.15)) (justify left bottom))
    )
    (fp_text user "${REFERENCE}" (at -0.95 3.168 180) (layer "F.Fab") hide
        (effects (font (size 0.7 0.7) (thickness 0.15)) (justify left bottom))
    )
    (fp_text user "License: Apache-2.0" (at -0.95 5.169 180) (layer "F.Fab") hide
        (effects (font (size 0.7 0.7) (thickness 0.15)) (justify left bottom))
    )
    (fp_rect (start -0.93 -0.47) (end 0.93 0.47)
      (stroke (width 0.05) (type solid)) (fill none) (layer "F.CrtYd"))
    (fp_rect (start -0.5 -0.25) (end 0.5 0.25)
      (stroke (width 0.15) (type solid)) (fill none) (layer "F.Fab"))
    (pad "1" smd roundrect (at -0.485 0 180) (size 0.59 0.64) (layers "F.Cu" "F.Paste" "F.Mask") (roundrect_rratio 0.25)
      (net 15 "PS_3V3") (pintype "passive"))
    (pad "2" smd roundrect (at 0.485 0 180) (size 0.59 0.64) (layers "F.Cu" "F.Paste" "F.Mask") (roundrect_rratio 0.25)
      (net 221 "/PCIE M2 key E /~{M2_PERST}") (pintype "passive"))
  )
	(footprint "kria-k26-devboard-footprints:SOT-563" (layer "F.Cu")
    (at 132.58 74.22 90)
    (property "Author" "Antmicro")
    (property "License" "Apache-2.0")
    (property "MPN" "82400152")
    (property "Manufacturer" "Würth Elektronik")
    (property "Sheetfile" "usb.kicad_sch")
    (property "Sheetname" "USB")
    (property "ki_description" "TVS diode")
    (property "ki_keywords" "SMT, DIODE, IC, ESD, TVS")
    (attr smd)
    (fp_text reference "U21" (at -2.07 -1.09 180) (layer "F.SilkS")
        (effects (font (size 0.7 0.7) (thickness 0.15)) (justify left bottom))
    )
    (fp_text value "82400152" (at 0 2 90) (layer "F.Fab") hide
        (effects (font (size 0.7 0.7) (thickness 0.15)) (justify left bottom))
    )
    (fp_text user "Author: Antmicro" (at -1.299 6.124 90) (layer "F.Fab") hide
        (effects (font (size 0.7 0.7) (thickness 0.15)) (justify left bottom))
    )
    (fp_text user "${REFERENCE}" (at -1.299 7.323 90) (layer "F.Fab") hide
        (effects (font (size 0.7 0.7) (thickness 0.15)) (justify left bottom))
    )
    (fp_text user "License: Apache-2.0" (at -1.299 4.924 90) (layer "F.Fab") hide
        (effects (font (size 0.7 0.7) (thickness 0.15)) (justify left bottom))
    )
    (fp_line (start -0.778 0.776) (end -0.778 0.949)
      (stroke (width 0.15) (type solid)) (layer "F.SilkS"))
    (fp_line (start -0.778 0.949) (end -0.424 0.949)
      (stroke (width 0.15) (type solid)) (layer "F.SilkS"))
    (fp_line (start -0.499 -0.974) (end -0.724 -0.778)
      (stroke (width 0.15) (type solid)) (layer "F.SilkS"))
    (fp_line (start 0.776 -0.974) (end 0.526 -0.974)
      (stroke (width 0.15) (type solid)) (layer "F.SilkS"))
    (fp_line (start 0.776 -0.974) (end 0.776 -0.778)
      (stroke (width 0.15) (type solid)) (layer "F.SilkS"))
    (fp_line (start 0.776 0.776) (end 0.776 0.972)
      (stroke (width 0.15) (type solid)) (layer "F.SilkS"))
    (fp_line (start 0.776 0.972) (end 0.526 0.972)
      (stroke (width 0.15) (type solid)) (layer "F.SilkS"))
    (fp_circle (center -0.903 -0.999) (end -0.952 -0.95)
      (stroke (width 0.15) (type solid)) (fill solid) (layer "F.SilkS"))
    (fp_rect (start 1.19 -1.12) (end -1.2 1.1)
      (stroke (width 0.05) (type solid)) (fill none) (layer "F.CrtYd"))
    (fp_line (start -0.653 -0.678) (end -0.653 0.847)
      (stroke (width 0.15) (type solid)) (layer "F.Fab"))
    (fp_line (start -0.453 -0.849) (end -0.653 -0.678)
      (stroke (width 0.15) (type solid)) (layer "F.Fab"))
    (fp_line (start -0.453 -0.849) (end 0.651 -0.849)
      (stroke (width 0.15) (type solid)) (layer "F.Fab"))
    (fp_line (start 0.651 -0.849) (end 0.651 0.847)
      (stroke (width 0.15) (type solid)) (layer "F.Fab"))
    (fp_line (start 0.651 0.847) (end -0.653 0.847)
      (stroke (width 0.15) (type solid)) (layer "F.Fab"))
    (pad "1" smd roundrect (at -0.749 -0.499) (size 0.3 0.6) (layers "F.Cu" "F.Paste" "F.Mask") (roundrect_rratio 0.25)
      (net 70 "/USB/USB2_P") (pintype "passive"))
    (pad "2" smd roundrect (at -0.749 0.001) (size 0.3 0.6) (layers "F.Cu" "F.Paste" "F.Mask") (roundrect_rratio 0.25)
      (net 1 "GND") (pintype "passive"))
    (pad "3" smd roundrect (at -0.749 0.497) (size 0.3 0.6) (layers "F.Cu" "F.Paste" "F.Mask") (roundrect_rratio 0.25)
      (net 69 "/USB/USB2_N") (pintype "passive"))
    (pad "4" smd roundrect (at 0.747 0.497) (size 0.3 0.6) (layers "F.Cu" "F.Paste" "F.Mask") (roundrect_rratio 0.25)
      (net 288 "/USB/USB2_TVS_N") (pintype "passive"))
    (pad "5" smd roundrect (at 0.747 0.001) (size 0.3 0.6) (layers "F.Cu" "F.Paste" "F.Mask") (roundrect_rratio 0.25)
      (net 85 "/USB/USB2_VBUS") (pintype "passive"))
    (pad "6" smd roundrect (at 0.747 -0.499) (size 0.3 0.6) (layers "F.Cu" "F.Paste" "F.Mask") (roundrect_rratio 0.25)
      (net 289 "/USB/USB2_TVS_P") (pintype "passive"))
  )
	(footprint "kria-k26-devboard-footprints:R_0402_1005Metric" (layer "F.Cu")
    (at 124.725 97.404)
    (descr "Resistor SMD 0402")
    (tags "resistor SMD 0402")
    (property "Author" "Antmicro")
    (property "License" "Apache-2.0")
    (property "MPN" "CR0402-FX-8061GLF")
    (property "Manufacturer" "Bourns")
    (property "Sheetfile" "usb.kicad_sch")
    (property "Sheetname" "USB")
    (property "Tolerance" "1%")
    (property "Val" "8k06")
    (property "ki_description" "8k06 resistor in 0402 package with 1% tolerance")
    (attr smd)
    (fp_text reference "R65" (at -1.095 -0.604) (layer "F.SilkS")
        (effects (font (size 0.7 0.7) (thickness 0.15)) (justify left bottom))
    )
    (fp_text value "R_8k06_0402" (at 0 1.4) (layer "F.Fab") hide
        (effects (font (size 0.7 0.7) (thickness 0.15)) (justify left bottom))
    )
    (fp_text user "${REFERENCE}" (at -0.95 3.168) (layer "F.Fab") hide
        (effects (font (size 0.7 0.7) (thickness 0.15)) (justify left bottom))
    )
    (fp_text user "Author: Antmicro" (at -0.95 4.169) (layer "F.Fab") hide
        (effects (font (size 0.7 0.7) (thickness 0.15)) (justify left bottom))
    )
    (fp_text user "License: Apache-2.0" (at -0.95 5.169) (layer "F.Fab") hide
        (effects (font (size 0.7 0.7) (thickness 0.15)) (justify left bottom))
    )
    (fp_rect (start -0.93 -0.47) (end 0.93 0.47)
      (stroke (width 0.05) (type solid)) (fill none) (layer "F.CrtYd"))
    (fp_rect (start -0.5 -0.25) (end 0.5 0.25)
      (stroke (width 0.15) (type solid)) (fill none) (layer "F.Fab"))
    (pad "1" smd roundrect (at -0.485 0) (size 0.59 0.64) (layers "F.Cu" "F.Paste" "F.Mask") (roundrect_rratio 0.25)
      (net 668 "Net-(U23-RBIAS)") (pintype "passive"))
    (pad "2" smd roundrect (at 0.485 0) (size 0.59 0.64) (layers "F.Cu" "F.Paste" "F.Mask") (roundrect_rratio 0.25)
      (net 1 "GND") (pintype "passive"))
  )
	(footprint "kria-k26-devboard-footprints:TP_SMD_0.75mm" (layer "F.Cu")
    (at 189.975 137.5)
    (property "Author" "Antmicro")
    (property "License" "Apache-2.0")
    (property "MPN" "")
    (property "Manufacturer" "")
    (property "Sheetfile" "dc-dc-conventers.kicad_sch")
    (property "Sheetname" "DC/DC conventers")
    (property "ki_description" "Test Point 0.75mm")
    (attr exclude_from_pos_files)
    (fp_text reference "TP42" (at 0.325 7.53 90) (layer "F.SilkS")
        (effects (font (size 0.7 0.7) (thickness 0.15)) (justify left bottom))
    )
    (fp_text value "TP_0.75mm_SMD" (at 0 1.2) (layer "F.Fab") hide
        (effects (font (size 0.7 0.7) (thickness 0.15)) (justify left bottom))
    )
    (fp_text user "Author: Antmicro" (at -0.4 3.901) (layer "F.Fab") hide
        (effects (font (size 0.7 0.7) (thickness 0.15)) (justify left bottom))
    )
    (fp_text user "${REFERENCE}" (at -0.4 2.7) (layer "F.Fab") hide
        (effects (font (size 0.7 0.7) (thickness 0.15)) (justify left bottom))
    )
    (fp_text user "License: Apache-2.0" (at -0.4 5.101) (layer "F.Fab") hide
        (effects (font (size 0.7 0.7) (thickness 0.15)) (justify left bottom))
    )
    (pad "1" smd circle (at 0 0) (size 0.75 0.75) (layers "F.Cu" "F.Mask")
      (net 771 "/Power Supply/DC/DC conventers/PL_1V2_OUT") (pinfunction "1") (pintype "passive"))
  )
	(footprint "kria-k26-devboard-footprints:C_2220_5650Metric" (layer "F.Cu")
    (at 176.95 82.95 90)
    (descr "Capacitor SMD 2220")
    (tags "capacitor SMD 2220")
    (property "Author" "Antmicro")
    (property "Dielectric" "")
    (property "License" "Apache-2.0")
    (property "MPN" "C5750X7S2A226M280KB")
    (property "Manufacturer" "TDK")
    (property "Sheetfile" "PoE.kicad_sch")
    (property "Sheetname" "PoE")
    (property "Val" "22u/100V")
    (property "Voltage" "")
    (property "ki_description" " ")
    (attr smd)
    (fp_text reference "C173" (at -1.4 -15.89 90) (layer "F.SilkS")
        (effects (font (size 0.7 0.7) (thickness 0.15)) (justify left bottom))
    )
    (fp_text value "C_22u_100V_2220" (at 0 3.9 90) (layer "F.Fab") hide
        (effects (font (size 0.7 0.7) (thickness 0.15)) (justify left bottom))
    )
    (fp_text user "${REFERENCE}" (at -3.7 5.9 90) (layer "F.Fab") hide
        (effects (font (size 0.7 0.7) (thickness 0.15)) (justify left bottom))
    )
    (fp_text user "License: Apache-2.0" (at -3.7 6.9 90) (layer "F.Fab") hide
        (effects (font (size 0.7 0.7) (thickness 0.15)) (justify left bottom))
    )
    (fp_text user "Author: Antmicro" (at -3.7 7.9 90) (layer "F.Fab") hide
        (effects (font (size 0.7 0.7) (thickness 0.15)) (justify left bottom))
    )
    (fp_line (start -1.415 -2.61) (end 1.415 -2.61)
      (stroke (width 0.15) (type solid)) (layer "F.SilkS"))
    (fp_line (start -1.415 2.61) (end 1.415 2.61)
      (stroke (width 0.15) (type solid)) (layer "F.SilkS"))
    (fp_rect (start -3.7 -2.95) (end 3.7 2.95)
      (stroke (width 0.05) (type solid)) (fill none) (layer "F.CrtYd"))
    (fp_rect (start -2.85 -2.5) (end 2.85 2.5)
      (stroke (width 0.15) (type solid)) (fill none) (layer "F.Fab"))
    (pad "1" smd roundrect (at -2.55 0 90) (size 1.8 5.4) (layers "F.Cu" "F.Paste" "F.Mask") (roundrect_rratio 0.138889)
      (net 9 "/Power Supply/PoE/VDD_POE_IN") (pintype "passive"))
    (pad "2" smd roundrect (at 2.55 0 90) (size 1.8 5.4) (layers "F.Cu" "F.Paste" "F.Mask") (roundrect_rratio 0.138889)
      (net 11 "GNDD") (pintype "passive"))
  )
	(footprint "kria-k26-devboard-footprints:TP_SMD_0.75mm" (layer "F.Cu")
    (at 141.325 64.35)
    (property "Author" "Antmicro")
    (property "License" "Apache-2.0")
    (property "MPN" "")
    (property "Manufacturer" "")
    (property "Sheetfile" "usbc-socket.kicad_sch")
    (property "Sheetname" "USB-C socket")
    (property "ki_description" "Test Point 0.75mm")
    (attr exclude_from_pos_files)
    (fp_text reference "TP44" (at -1.345 -0.45) (layer "F.SilkS")
        (effects (font (size 0.7 0.7) (thickness 0.15)) (justify left bottom))
    )
    (fp_text value "TP_0.75mm_SMD" (at 0 1.2) (layer "F.Fab") hide
        (effects (font (size 0.7 0.7) (thickness 0.15)) (justify left bottom))
    )
    (fp_text user "${REFERENCE}" (at -0.4 2.7) (layer "F.Fab") hide
        (effects (font (size 0.7 0.7) (thickness 0.15)) (justify left bottom))
    )
    (fp_text user "Author: Antmicro" (at -0.4 3.901) (layer "F.Fab") hide
        (effects (font (size 0.7 0.7) (thickness 0.15)) (justify left bottom))
    )
    (fp_text user "License: Apache-2.0" (at -0.4 5.101) (layer "F.Fab") hide
        (effects (font (size 0.7 0.7) (thickness 0.15)) (justify left bottom))
    )
    (pad "1" smd circle (at 0 0) (size 0.75 0.75) (layers "F.Cu" "F.Mask")
      (net 228 "/Power Supply/Supply ORing/PD_VBUS") (pinfunction "1") (pintype "passive"))
  )
	(footprint "kria-k26-devboard-footprints:R_Array_4x0201_Panasonic_EXB18V" (layer "F.Cu")
    (at 97.7457 118.0032 -90)
    (property "Author" "Antmicro")
    (property "License" "Apache-2.0")
    (property "MPN" "EXB-18V330JX")
    (property "Manufacturer" "Panasonic")
    (property "Sheetfile" "sd-3-card.kicad_sch")
    (property "Sheetname" "SD 3.0 card")
    (property "Val" "R_4x33R_0201")
    (attr smd)
    (fp_text reference "R15" (at 3.0068 -0.4143 90) (layer "F.SilkS")
        (effects (font (size 0.7 0.7) (thickness 0.15)) (justify left bottom))
    )
    (fp_text value "R_4x33R_0201_array" (at -1.1 1.8 -90) (layer "F.Fab") hide
        (effects (font (size 0.7 0.7) (thickness 0.15)) (justify left bottom))
    )
    (fp_text user "Author: Antmicro" (at -1.051 4.599 -90) (layer "F.Fab") hide
        (effects (font (size 0.7 0.7) (thickness 0.15)) (justify left bottom))
    )
    (fp_text user "License: Apache-2.0" (at -1.051 6 -90) (layer "F.Fab") hide
        (effects (font (size 0.7 0.7) (thickness 0.15)) (justify left bottom))
    )
    (fp_text user "${REFERENCE}" (at -1.051 3.2 -90) (layer "F.Fab") hide
        (effects (font (size 0.7 0.7) (thickness 0.15)) (justify left bottom))
    )
    (fp_line (start -0.8 -0.45) (end -0.8 0.45)
      (stroke (width 0.12) (type solid)) (layer "F.SilkS"))
    (fp_line (start 0.8 -0.45) (end 0.8 0.45)
      (stroke (width 0.12) (type solid)) (layer "F.SilkS"))
    (fp_rect (start -0.898 -0.66) (end 0.898 0.65)
      (stroke (width 0.05) (type solid)) (fill none) (layer "F.CrtYd"))
    (pad "1" smd roundrect (at -0.6 0.298 270) (size 0.2 0.4) (layers "F.Cu" "F.Paste" "F.Mask") (roundrect_rratio 0.25)
      (net 115 "/SD 3.0 card/MIO49") (pinfunction "R1.1") (pintype "passive"))
    (pad "2" smd roundrect (at -0.202 0.298 270) (size 0.2 0.4) (layers "F.Cu" "F.Paste" "F.Mask") (roundrect_rratio 0.25)
      (net 114 "/SD 3.0 card/MIO48") (pinfunction "R2.1") (pintype "passive"))
    (pad "3" smd roundrect (at 0.2 0.298 270) (size 0.2 0.4) (layers "F.Cu" "F.Paste" "F.Mask") (roundrect_rratio 0.25)
      (net 113 "/SD 3.0 card/MIO47") (pinfunction "R3.1") (pintype "passive"))
    (pad "4" smd roundrect (at 0.598 0.298 270) (size 0.2 0.4) (layers "F.Cu" "F.Paste" "F.Mask") (roundrect_rratio 0.25)
      (net 118 "/SD 3.0 card/MIO46") (pinfunction "R4.1") (pintype "passive"))
    (pad "5" smd roundrect (at 0.598 -0.3 270) (size 0.2 0.4) (layers "F.Cu" "F.Paste" "F.Mask") (roundrect_rratio 0.25)
      (net 638 "Net-(R15-R4.2)") (pinfunction "R4.2") (pintype "passive"))
    (pad "6" smd roundrect (at 0.2 -0.3 270) (size 0.2 0.4) (layers "F.Cu" "F.Paste" "F.Mask") (roundrect_rratio 0.25)
      (net 639 "Net-(R15-R3.2)") (pinfunction "R3.2") (pintype "passive"))
    (pad "7" smd roundrect (at -0.202 -0.3 270) (size 0.2 0.4) (layers "F.Cu" "F.Paste" "F.Mask") (roundrect_rratio 0.25)
      (net 640 "Net-(R15-R2.2)") (pinfunction "R2.2") (pintype "passive"))
    (pad "8" smd roundrect (at -0.6 -0.3 270) (size 0.2 0.4) (layers "F.Cu" "F.Paste" "F.Mask") (roundrect_rratio 0.25)
      (net 641 "Net-(R15-R1.2)") (pinfunction "R1.2") (pintype "passive"))
  )
	(footprint "kria-k26-devboard-footprints:LED_0603_1608Metric_G" (layer "F.Cu")
    (at 183.36 78.17 180)
    (descr "LED SMD 0603 Green")
    (tags "LED SMD 0603 Green")
    (property "Author" "Antmicro")
    (property "Color" "Green")
    (property "License" "Apache-2.0")
    (property "MPN" "LG L29K-G2J1-24-Z")
    (property "Manufacturer" "OSRAM")
    (property "Sheetfile" "PoE.kicad_sch")
    (property "Sheetname" "PoE")
    (property "ki_description" "LED, Green, SMT, 0603, 20 mA, 2.1 V, 570 nm")
    (property "ki_keywords" "0603, SMT, DIODE, SEMICONDUCTOR, UNICOLOR")
    (attr smd)
    (fp_text reference "D11" (at -2.04 1.12 90) (layer "F.SilkS")
        (effects (font (size 0.7 0.7) (thickness 0.15)) (justify right bottom))
    )
    (fp_text value "LED_G_0603_LG_L29K-G2J1-24-Z" (at 0 1.6) (layer "F.Fab") hide
        (effects (font (size 0.7 0.7) (thickness 0.15)) (justify right bottom))
    )
    (fp_text user "License: Apache-2.0" (at -1.31 5.769) (layer "F.Fab") hide
        (effects (font (size 0.7 0.7) (thickness 0.15)) (justify right bottom))
    )
    (fp_text user "${REFERENCE}" (at -1.31 3.769) (layer "F.Fab") hide
        (effects (font (size 0.7 0.7) (thickness 0.15)) (justify right bottom))
    )
    (fp_text user "Author: Antmicro" (at -1.31 4.769) (layer "F.Fab") hide
        (effects (font (size 0.7 0.7) (thickness 0.15)) (justify right bottom))
    )
    (fp_line (start -0.27 -0.35) (end 0.27 -0.35)
      (stroke (width 0.15) (type solid)) (layer "F.SilkS"))
    (fp_line (start -0.27 0.351) (end 0.27 0.351)
      (stroke (width 0.15) (type solid)) (layer "F.SilkS"))
    (fp_line (start -0.106328 -0.200008) (end -0.106328 0.199992)
      (stroke (width 0.1) (type solid)) (layer "F.SilkS"))
    (fp_line (start -0.106328 -0.200008) (end 0.093672 -0.000008)
      (stroke (width 0.1) (type solid)) (layer "F.SilkS"))
    (fp_line (start -0.106328 -0.000008) (end -0.29 0)
      (stroke (width 0.1) (type solid)) (layer "F.SilkS"))
    (fp_line (start 0.093672 -0.200008) (end 0.093672 0.199992)
      (stroke (width 0.1) (type solid)) (layer "F.SilkS"))
    (fp_line (start 0.093672 -0.000008) (end -0.106328 0.199992)
      (stroke (width 0.1) (type solid)) (layer "F.SilkS"))
    (fp_line (start 0.093672 -0.000008) (end 0.293672 -0.000008)
      (stroke (width 0.1) (type solid)) (layer "F.SilkS"))
    (fp_line (start 1.25 0.32) (end 1.25 -0.32)
      (stroke (width 0.15) (type solid)) (layer "F.SilkS"))
    (fp_rect (start 1.26 0.65) (end -1.26 -0.65)
      (stroke (width 0.05) (type solid)) (fill none) (layer "F.CrtYd"))
    (fp_line (start -0.599 0) (end -0.201 0)
      (stroke (width 0.15) (type solid)) (layer "F.Fab"))
    (fp_line (start -0.201 -0.2) (end -0.201 0)
      (stroke (width 0.15) (type solid)) (layer "F.Fab"))
    (fp_line (start -0.201 0) (end -0.201 0.202)
      (stroke (width 0.15) (type solid)) (layer "F.Fab"))
    (fp_line (start -0.201 0.202) (end 0.101 0)
      (stroke (width 0.15) (type solid)) (layer "F.Fab"))
    (fp_line (start 0.101 0) (end -0.201 -0.2)
      (stroke (width 0.15) (type solid)) (layer "F.Fab"))
    (fp_line (start 0.199 -0.2) (end 0.199 -0.1)
      (stroke (width 0.15) (type solid)) (layer "F.Fab"))
    (fp_line (start 0.199 0) (end 0.597 0)
      (stroke (width 0.15) (type solid)) (layer "F.Fab"))
    (fp_line (start 0.199 0.202) (end 0.199 -0.1)
      (stroke (width 0.15) (type solid)) (layer "F.Fab"))
    (fp_rect (start -0.848 -0.4) (end 0.85 0.402)
      (stroke (width 0.15) (type solid)) (fill none) (layer "F.Fab"))
    (pad "1" smd rect (at -0.75 0) (size 0.8 0.8) (layers "F.Cu" "F.Paste" "F.Mask")
      (net 7 "Net-(D11-Pad1)") (pintype "passive"))
    (pad "2" smd rect (at 0.75 0) (size 0.8 0.8) (layers "F.Cu" "F.Paste" "F.Mask")
      (net 11 "GNDD") (pinfunction "2") (pintype "passive"))
  )
)
